(kicad_pcb
	(version 20260206)
	(generator "pcbnew")
	(generator_version "10.0")
	(general
		(thickness 1.5755)
		(legacy_teardrops no)
	)
	(paper "A4")
	(title_block
		(title "gnss-neo-m9n — 844-XXXXX_FAB_NEO-M9N_MODULE.PcbDoc")
		(comment 1 "Time Appliance Project (Time Card) / footprints 12-26 of 33")
	)
	(layers
		(0 "F.Cu" signal "L01-Top Layer")
		(4 "In1.Cu" signal "L02-Inner Layer")
		(6 "In2.Cu" signal "L03-Inner Layer")
		(2 "B.Cu" signal "L04-Bottom Layer")
		(9 "F.Adhes" user "F.Adhesive")
		(11 "B.Adhes" user "B.Adhesive")
		(13 "F.Paste" user "Top Paste")
		(15 "B.Paste" user "Bottom Paste")
		(5 "F.SilkS" user "Top Overlay")
		(7 "B.SilkS" user "Bottom Overlay")
		(1 "F.Mask" user "Top Solder")
		(3 "B.Mask" user "Bottom Solder")
		(17 "Dwgs.User" user "User.Drawings")
		(19 "Cmts.User" user "User.Comments")
		(21 "Eco1.User" user "User.Eco1")
		(23 "Eco2.User" user "User.Eco2")
		(25 "Edge.Cuts" user)
		(27 "Margin" user)
		(31 "F.CrtYd" user "Top Courtyard")
		(29 "B.CrtYd" user "Bottom Courtyard")
		(35 "F.Fab" user "Top Component Outline")
		(33 "B.Fab" user "Bottom Component Outline 2")
		(39 "User.1" user "M01_PCB_Outline")
	)
	(footprint "MyLibrary:r0603"
		(layer "F.Cu")
		(at 125.9151 104.187745 90)
		(property "Reference" "R4"
			(at -0.910793 1.877795 0)
			(unlocked yes)
			(layer "F.SilkS")
			(effects
				(font
					(size 0.635 0.635)
					(thickness 0.1778)
				)
			)
		)
		(property "Value" "10 OHM 1/4W 0603"
			(at -5.216993 5.192245 0)
			(unlocked yes)
			(layer "F.SilkS")
			(hide yes)
			(effects
				(font
					(size 0.635 0.635)
					(thickness 0.1778)
				)
			)
		)
		(sheetname "846-XXXXX_SCH_NEO-M9N_MODULE_2_RECEIVER")
		(sheetfile "846-XXXXX_SCH_NEO-M9N_MODULE_2_RECEIVER.kicad_sch")
		(duplicate_pad_numbers_are_jumpers no)
		(fp_line
			(start 1.2954 -0.6858)
			(end 1.2954 0.6858)
			(stroke
				(width 0.1778)
				(type solid)
			)
			(layer "F.SilkS")
		)
		(fp_line
			(start -1.2954 -0.6858)
			(end 1.2954 -0.6858)
			(stroke
				(width 0.1778)
				(type solid)
			)
			(layer "F.SilkS")
		)
		(fp_line
			(start -1.2954 -0.6858)
			(end -1.2954 0.6858)
			(stroke
				(width 0.1778)
				(type solid)
			)
			(layer "F.SilkS")
		)
		(fp_line
			(start -1.2954 0.6858)
			(end 1.2954 0.6858)
			(stroke
				(width 0.1778)
				(type solid)
			)
			(layer "F.SilkS")
		)
		(pad "1" smd rect
			(at -0.75 0 90)
			(size 0.6 0.9)
			(layers "F.Cu" "F.Mask" "F.Paste")
			(net "NetQ1_3")
		)
		(pad "2" smd rect
			(at 0.75 0 90)
			(size 0.6 0.9)
			(layers "F.Cu" "F.Mask" "F.Paste")
			(net "NetC5_2")
		)
	)
	(footprint "MyLibrary:r0402"
		(layer "F.Cu")
		(at 160.8151 109.976095 90)
		(property "Reference" "R2"
			(at 2.477805 0.022443 90)
			(unlocked yes)
			(layer "F.SilkS")
			(effects
				(font
					(size 0.635 0.635)
					(thickness 0.1778)
				)
			)
		)
		(property "Value" "10K 1/8W 0402"
			(at 4.938495 2.168983 90)
			(unlocked yes)
			(layer "F.SilkS")
			(hide yes)
			(effects
				(font
					(size 0.635 0.635)
					(thickness 0.1778)
				)
			)
		)
		(sheetname "846-XXXXX_SCH_NEO-M9N_MODULE_2_RECEIVER")
		(sheetfile "846-XXXXX_SCH_NEO-M9N_MODULE_2_RECEIVER.kicad_sch")
		(duplicate_pad_numbers_are_jumpers no)
		(fp_line
			(start 0.9906 -0.5334)
			(end 0.9906 0.5334)
			(stroke
				(width 0.1778)
				(type solid)
			)
			(layer "F.SilkS")
		)
		(fp_line
			(start -0.9906 -0.5334)
			(end 0.9906 -0.5334)
			(stroke
				(width 0.1778)
				(type solid)
			)
			(layer "F.SilkS")
		)
		(fp_line
			(start -0.9906 -0.5334)
			(end -0.9906 0.5334)
			(stroke
				(width 0.1778)
				(type solid)
			)
			(layer "F.SilkS")
		)
		(fp_line
			(start -0.9906 0.5334)
			(end 0.9906 0.5334)
			(stroke
				(width 0.1778)
				(type solid)
			)
			(layer "F.SilkS")
		)
		(pad "1" smd rect
			(at -0.5 0 90)
			(size 0.5 0.6)
			(layers "F.Cu" "F.Mask" "F.Paste")
			(net "GND")
		)
		(pad "2" smd rect
			(at 0.5 0 90)
			(size 0.5 0.6)
			(layers "F.Cu" "F.Mask" "F.Paste")
			(net "NetLED1_2")
		)
	)
	(footprint "MyLibrary:TP1MM"
		(layer "F.Cu")
		(at 147.1151 113.676095)
		(property "Reference" "TP9"
			(at -0.022443 1.977805 270)
			(unlocked yes)
			(layer "F.SilkS")
			(effects
				(font
					(size 0.635 0.635)
					(thickness 0.1778)
				)
			)
		)
		(property "Value" "1MM"
			(at -2.092793 1.790085 270)
			(unlocked yes)
			(layer "F.SilkS")
			(hide yes)
			(effects
				(font
					(size 0.635 0.635)
					(thickness 0.1778)
				)
			)
		)
		(sheetname "846-XXXXX_SCH_NEO-M9N_MODULE_2_RECEIVER")
		(sheetfile "846-XXXXX_SCH_NEO-M9N_MODULE_2_RECEIVER.kicad_sch")
		(duplicate_pad_numbers_are_jumpers no)
		(pad "1" smd circle
			(at 0 0)
			(size 1 1)
			(layers "F.Cu" "F.Mask" "F.Paste")
			(net "SCL_SPI_CLK")
			(solder_paste_margin -100)
			(thermal_bridge_angle 90)
		)
	)
	(footprint "MyLibrary:TP1MM"
		(layer "F.Cu")
		(at 146.01515 95.576095)
		(property "Reference" "TP4"
			(at 0.122393 -1.677805 90)
			(unlocked yes)
			(layer "F.SilkS")
			(effects
				(font
					(size 0.635 0.635)
					(thickness 0.1778)
				)
			)
		)
		(property "Value" "1MM"
			(at -2.092793 1.790085 270)
			(unlocked yes)
			(layer "F.SilkS")
			(hide yes)
			(effects
				(font
					(size 0.635 0.635)
					(thickness 0.1778)
				)
			)
		)
		(sheetname "846-XXXXX_SCH_NEO-M9N_MODULE_2_RECEIVER")
		(sheetfile "846-XXXXX_SCH_NEO-M9N_MODULE_2_RECEIVER.kicad_sch")
		(duplicate_pad_numbers_are_jumpers no)
		(pad "1" smd circle
			(at 0 0)
			(size 1 1)
			(layers "F.Cu" "F.Mask" "F.Paste")
			(net "VDD_USB")
			(solder_paste_margin -100)
			(thermal_bridge_angle 90)
		)
	)
	(footprint "MyLibrary:c0402"
		(layer "F.Cu")
		(at 128.2151 103.437745 180)
		(property "Reference" "C5"
			(at -2.177795 -0.122443 0)
			(unlocked yes)
			(layer "F.SilkS")
			(effects
				(font
					(size 0.635 0.635)
					(thickness 0.1778)
				)
			)
		)
		(property "Value" "10nF 50V 0402"
			(at 5.065455 2.118183 180)
			(unlocked yes)
			(layer "F.SilkS")
			(hide yes)
			(effects
				(font
					(size 0.635 0.635)
					(thickness 0.1778)
				)
			)
		)
		(sheetname "846-XXXXX_SCH_NEO-M9N_MODULE_2_RECEIVER")
		(sheetfile "846-XXXXX_SCH_NEO-M9N_MODULE_2_RECEIVER.kicad_sch")
		(duplicate_pad_numbers_are_jumpers no)
		(fp_line
			(start 0.9906 0.4826)
			(end -0.9906 0.4826)
			(stroke
				(width 0.1778)
				(type solid)
			)
			(layer "F.SilkS")
		)
		(fp_line
			(start 0.9906 -0.4826)
			(end 0.9906 0.4826)
			(stroke
				(width 0.1778)
				(type solid)
			)
			(layer "F.SilkS")
		)
		(fp_line
			(start 0.9906 -0.4826)
			(end -0.9906 -0.4826)
			(stroke
				(width 0.1778)
				(type solid)
			)
			(layer "F.SilkS")
		)
		(fp_line
			(start -0.9906 -0.4826)
			(end -0.9906 0.4826)
			(stroke
				(width 0.1778)
				(type solid)
			)
			(layer "F.SilkS")
		)
		(pad "1" smd rect
			(at -0.5 0 180)
			(size 0.5 0.5)
			(layers "F.Cu" "F.Mask" "F.Paste")
			(net "GND")
		)
		(pad "2" smd rect
			(at 0.5 0 180)
			(size 0.5 0.5)
			(layers "F.Cu" "F.Mask" "F.Paste")
			(net "NetC5_2")
		)
	)
	(footprint "MyLibrary:r0402"
		(layer "F.Cu")
		(at 175.97619 101.376095 -90)
		(property "Reference" "R8"
			(at 1.622443 -0.116705 0)
			(unlocked yes)
			(layer "F.SilkS")
			(effects
				(font
					(size 0.635 0.635)
					(thickness 0.1778)
				)
			)
		)
		(property "Value" "0 ohm 0402"
			(at 2.907155 2.168983 270)
			(unlocked yes)
			(layer "F.SilkS")
			(hide yes)
			(effects
				(font
					(size 0.635 0.635)
					(thickness 0.1778)
				)
			)
		)
		(sheetname "846-XXXXX_SCH_NEO-M9N_MODULE_2_RECEIVER")
		(sheetfile "846-XXXXX_SCH_NEO-M9N_MODULE_2_RECEIVER.kicad_sch")
		(duplicate_pad_numbers_are_jumpers no)
		(fp_line
			(start -0.9906 0.5334)
			(end -0.9906 -0.5334)
			(stroke
				(width 0.1778)
				(type solid)
			)
			(layer "F.SilkS")
		)
		(fp_line
			(start 0.9906 0.5334)
			(end -0.9906 0.5334)
			(stroke
				(width 0.1778)
				(type solid)
			)
			(layer "F.SilkS")
		)
		(fp_line
			(start 0.9906 0.5334)
			(end 0.9906 -0.5334)
			(stroke
				(width 0.1778)
				(type solid)
			)
			(layer "F.SilkS")
		)
		(fp_line
			(start 0.9906 -0.5334)
			(end -0.9906 -0.5334)
			(stroke
				(width 0.1778)
				(type solid)
			)
			(layer "F.SilkS")
		)
		(pad "1" smd rect
			(at -0.5 0 270)
			(size 0.5 0.6)
			(layers "F.Cu" "F.Mask" "F.Paste")
			(net "TX_GPS")
		)
		(pad "2" smd rect
			(at 0.5 0 270)
			(size 0.5 0.6)
			(layers "F.Cu" "F.Mask" "F.Paste")
			(net "TX_GPS_CONN")
		)
	)
	(footprint "MyLibrary:TP1MM"
		(layer "F.Cu")
		(at 153.1151 97.076095)
		(property "Reference" "TP7"
			(at 1.977805 0.022443 0)
			(unlocked yes)
			(layer "F.SilkS")
			(effects
				(font
					(size 0.635 0.635)
					(thickness 0.1778)
				)
			)
		)
		(property "Value" "1MM"
			(at -2.092783 1.790085 270)
			(unlocked yes)
			(layer "F.SilkS")
			(hide yes)
			(effects
				(font
					(size 0.635 0.635)
					(thickness 0.1778)
				)
			)
		)
		(sheetname "846-XXXXX_SCH_NEO-M9N_MODULE_2_RECEIVER")
		(sheetfile "846-XXXXX_SCH_NEO-M9N_MODULE_2_RECEIVER.kicad_sch")
		(duplicate_pad_numbers_are_jumpers no)
		(pad "1" smd circle
			(at 0 0)
			(size 1 1)
			(layers "F.Cu" "F.Mask" "F.Paste")
			(net "SAFEBOOT_N")
			(solder_paste_margin -100)
			(thermal_bridge_angle 90)
		)
	)
	(footprint "MyLibrary:TP1MM"
		(layer "F.Cu")
		(at 139.7151 113.676095)
		(property "Reference" "TP6"
			(at -0.022443 1.977805 270)
			(unlocked yes)
			(layer "F.SilkS")
			(effects
				(font
					(size 0.635 0.635)
					(thickness 0.1778)
				)
			)
		)
		(property "Value" "1MM"
			(at -2.092793 1.790085 270)
			(unlocked yes)
			(layer "F.SilkS")
			(hide yes)
			(effects
				(font
					(size 0.635 0.635)
					(thickness 0.1778)
				)
			)
		)
		(sheetname "846-XXXXX_SCH_NEO-M9N_MODULE_2_RECEIVER")
		(sheetfile "846-XXXXX_SCH_NEO-M9N_MODULE_2_RECEIVER.kicad_sch")
		(duplicate_pad_numbers_are_jumpers no)
		(pad "1" smd circle
			(at 0 0)
			(size 1 1)
			(layers "F.Cu" "F.Mask" "F.Paste")
			(net "LNA_EN")
			(solder_paste_margin -100)
			(thermal_bridge_angle 90)
		)
	)
	(footprint "MyLibrary:r0402"
		(layer "F.Cu")
		(at 144.2151 96.576095 90)
		(property "Reference" "R1"
			(at 2.077795 0.022393 90)
			(unlocked yes)
			(layer "F.SilkS")
			(effects
				(font
					(size 0.635 0.635)
					(thickness 0.1778)
				)
			)
		)
		(property "Value" "0 ohm 0402"
			(at 2.907145 2.168983 90)
			(unlocked yes)
			(layer "F.SilkS")
			(hide yes)
			(effects
				(font
					(size 0.635 0.635)
					(thickness 0.1778)
				)
			)
		)
		(sheetname "846-XXXXX_SCH_NEO-M9N_MODULE_2_RECEIVER")
		(sheetfile "846-XXXXX_SCH_NEO-M9N_MODULE_2_RECEIVER.kicad_sch")
		(duplicate_pad_numbers_are_jumpers no)
		(fp_line
			(start 0.9906 -0.5334)
			(end 0.9906 0.5334)
			(stroke
				(width 0.1778)
				(type solid)
			)
			(layer "F.SilkS")
		)
		(fp_line
			(start -0.9906 -0.5334)
			(end 0.9906 -0.5334)
			(stroke
				(width 0.1778)
				(type solid)
			)
			(layer "F.SilkS")
		)
		(fp_line
			(start -0.9906 -0.5334)
			(end -0.9906 0.5334)
			(stroke
				(width 0.1778)
				(type solid)
			)
			(layer "F.SilkS")
		)
		(fp_line
			(start -0.9906 0.5334)
			(end 0.9906 0.5334)
			(stroke
				(width 0.1778)
				(type solid)
			)
			(layer "F.SilkS")
		)
		(pad "1" smd rect
			(at -0.5 0 90)
			(size 0.5 0.6)
			(layers "F.Cu" "F.Mask" "F.Paste")
			(net "VDD_USB")
		)
		(pad "2" smd rect
			(at 0.5 0 90)
			(size 0.5 0.6)
			(layers "F.Cu" "F.Mask" "F.Paste")
			(net "GND")
		)
	)
	(footprint "MyLibrary:TP1MM"
		(layer "F.Cu")
		(at 173.42105 99.276095 90)
		(property "Reference" "TP10"
			(at -0.022443 -2.22815 0)
			(unlocked yes)
			(layer "F.SilkS")
			(effects
				(font
					(size 0.635 0.635)
					(thickness 0.1778)
				)
			)
		)
		(property "Value" "1MM"
			(at -2.092783 1.790075 0)
			(unlocked yes)
			(layer "F.SilkS")
			(hide yes)
			(effects
				(font
					(size 0.635 0.635)
					(thickness 0.1778)
				)
			)
		)
		(sheetname "846-XXXXX_SCH_NEO-M9N_MODULE_2_RECEIVER")
		(sheetfile "846-XXXXX_SCH_NEO-M9N_MODULE_2_RECEIVER.kicad_sch")
		(duplicate_pad_numbers_are_jumpers no)
		(pad "1" smd circle
			(at 0 0 90)
			(size 1 1)
			(layers "F.Cu" "F.Mask" "F.Paste")
			(net "RX_GPS")
			(solder_paste_margin -100)
			(thermal_bridge_angle 90)
		)
	)
	(footprint "LotusSound:SOT23"
		(layer "F.Cu")
		(at 127.0151 107.876095 90)
		(property "Reference" "Q1"
			(at -1.222443 -1.722195 0)
			(unlocked yes)
			(layer "F.SilkS")
			(effects
				(font
					(size 0.635 0.635)
					(thickness 0.1778)
				)
			)
		)
		(property "Value" "DMG2302UKQ-7"
			(at 7.883825 3.419602 90)
			(unlocked yes)
			(layer "F.SilkS")
			(hide yes)
			(effects
				(font
					(size 1.524 1.524)
					(thickness 0.254)
				)
			)
		)
		(sheetname "846-XXXXX_SCH_NEO-M9N_MODULE_2_RECEIVER")
		(sheetfile "846-XXXXX_SCH_NEO-M9N_MODULE_2_RECEIVER.kicad_sch")
		(duplicate_pad_numbers_are_jumpers no)
		(fp_line
			(start 0.5334 -1.8542)
			(end 0.5334 -0.9525)
			(stroke
				(width 0.1524)
				(type solid)
			)
			(layer "F.SilkS")
		)
		(fp_line
			(start -0.5334 -1.8542)
			(end 0.5334 -1.8542)
			(stroke
				(width 0.1524)
				(type solid)
			)
			(layer "F.SilkS")
		)
		(fp_line
			(start -0.5334 -1.8542)
			(end -0.5334 -0.9525)
			(stroke
				(width 0.1524)
				(type solid)
			)
			(layer "F.SilkS")
		)
		(fp_line
			(start 1.7526 -0.9525)
			(end 1.7526 0.9525)
			(stroke
				(width 0.1524)
				(type solid)
			)
			(layer "F.SilkS")
		)
		(fp_line
			(start 0.5334 -0.9525)
			(end 1.7526 -0.9525)
			(stroke
				(width 0.1524)
				(type solid)
			)
			(layer "F.SilkS")
		)
		(fp_line
			(start -1.7526 -0.9525)
			(end -0.5334 -0.9525)
			(stroke
				(width 0.1524)
				(type solid)
			)
			(layer "F.SilkS")
		)
		(fp_line
			(start -1.7526 -0.9525)
			(end -1.7526 0.9525)
			(stroke
				(width 0.1524)
				(type solid)
			)
			(layer "F.SilkS")
		)
		(fp_line
			(start 1.4484 0.9525)
			(end 1.7526 0.9525)
			(stroke
				(width 0.1524)
				(type solid)
			)
			(layer "F.SilkS")
		)
		(fp_line
			(start 1.4484 0.9525)
			(end 1.4484 1.8542)
			(stroke
				(width 0.1524)
				(type solid)
			)
			(layer "F.SilkS")
		)
		(fp_line
			(start -1.4484 0.9525)
			(end -1.4484 1.8542)
			(stroke
				(width 0.1524)
				(type solid)
			)
			(layer "F.SilkS")
		)
		(fp_line
			(start -1.7526 0.9525)
			(end -1.4484 0.9525)
			(stroke
				(width 0.1524)
				(type solid)
			)
			(layer "F.SilkS")
		)
		(fp_line
			(start -1.4484 1.8542)
			(end 1.4484 1.8542)
			(stroke
				(width 0.1524)
				(type solid)
			)
			(layer "F.SilkS")
		)
		(fp_circle
			(center -1.778 1.524)
			(end -1.7018 1.524)
			(stroke
				(width 0.1778)
				(type solid)
			)
			(fill no)
			(layer "F.SilkS")
		)
		(pad "1" smd rect
			(at -0.915 0.9652 90)
			(size 0.5588 1.27)
			(layers "F.Cu" "F.Mask" "F.Paste")
			(net "NetQ1_1")
		)
		(pad "2" smd rect
			(at 0.915 0.9652 90)
			(size 0.5588 1.27)
			(layers "F.Cu" "F.Mask" "F.Paste")
			(net "+5V")
		)
		(pad "3" smd rect
			(at 0 -0.9652 90)
			(size 0.5588 1.27)
			(layers "F.Cu" "F.Mask" "F.Paste")
			(net "NetQ1_3")
		)
	)
	(footprint "MyLibrary:TP1MM"
		(layer "F.Cu")
		(at 147.11497 97.161445)
		(property "Reference" "TP3"
			(at 0.022563 -1.663155 90)
			(unlocked yes)
			(layer "F.SilkS")
			(effects
				(font
					(size 0.635 0.635)
					(thickness 0.1778)
				)
			)
		)
		(property "Value" "1MM"
			(at -2.092783 1.790085 270)
			(unlocked yes)
			(layer "F.SilkS")
			(hide yes)
			(effects
				(font
					(size 0.635 0.635)
					(thickness 0.1778)
				)
			)
		)
		(sheetname "846-XXXXX_SCH_NEO-M9N_MODULE_2_RECEIVER")
		(sheetfile "846-XXXXX_SCH_NEO-M9N_MODULE_2_RECEIVER.kicad_sch")
		(duplicate_pad_numbers_are_jumpers no)
		(pad "1" smd circle
			(at 0 0)
			(size 1 1)
			(layers "F.Cu" "F.Mask" "F.Paste")
			(net "USB_DP")
			(solder_paste_margin -100)
			(thermal_bridge_angle 90)
		)
	)
	(footprint "MyLibrary:TP1MM"
		(layer "F.Cu")
		(at 145.4151 113.676095)
		(property "Reference" "TP8"
			(at -0.022443 1.977805 270)
			(unlocked yes)
			(layer "F.SilkS")
			(effects
				(font
					(size 0.635 0.635)
					(thickness 0.1778)
				)
			)
		)
		(property "Value" "1MM"
			(at -2.092783 1.790085 270)
			(unlocked yes)
			(layer "F.SilkS")
			(hide yes)
			(effects
				(font
					(size 0.635 0.635)
					(thickness 0.1778)
				)
			)
		)
		(sheetname "846-XXXXX_SCH_NEO-M9N_MODULE_2_RECEIVER")
		(sheetfile "846-XXXXX_SCH_NEO-M9N_MODULE_2_RECEIVER.kicad_sch")
		(duplicate_pad_numbers_are_jumpers no)
		(pad "1" smd circle
			(at 0 0)
			(size 1 1)
			(layers "F.Cu" "F.Mask" "F.Paste")
			(net "SDA_SPI_CS_N")
			(solder_paste_margin -100)
			(thermal_bridge_angle 90)
		)
	)
	(footprint "MyLibrary:TP1MM"
		(layer "F.Cu")
		(at 175.97619 99.276095 90)
		(property "Reference" "TP11"
			(at -0.022443 2.11671 0)
			(unlocked yes)
			(layer "F.SilkS")
			(effects
				(font
					(size 0.635 0.635)
					(thickness 0.1778)
				)
			)
		)
		(property "Value" "1MM"
			(at -2.092783 1.790085 0)
			(unlocked yes)
			(layer "F.SilkS")
			(hide yes)
			(effects
				(font
					(size 0.635 0.635)
					(thickness 0.1778)
				)
			)
		)
		(sheetname "846-XXXXX_SCH_NEO-M9N_MODULE_2_RECEIVER")
		(sheetfile "846-XXXXX_SCH_NEO-M9N_MODULE_2_RECEIVER.kicad_sch")
		(duplicate_pad_numbers_are_jumpers no)
		(pad "1" smd circle
			(at 0 0 90)
			(size 1 1)
			(layers "F.Cu" "F.Mask" "F.Paste")
			(net "TX_GPS")
			(solder_paste_margin -100)
			(thermal_bridge_angle 90)
		)
	)
	(footprint "MyLibrary:r0402"
		(layer "F.Cu")
		(at 167.7151 109.976095 90)
		(property "Reference" "R3"
			(at 2.277805 0.122433 90)
			(unlocked yes)
			(layer "F.SilkS")
			(effects
				(font
					(size 0.635 0.635)
					(thickness 0.1778)
				)
			)
		)
		(property "Value" "10K 1/8W 0402"
			(at 4.938495 2.168983 90)
			(unlocked yes)
			(layer "F.SilkS")
			(hide yes)
			(effects
				(font
					(size 0.635 0.635)
					(thickness 0.1778)
				)
			)
		)
		(sheetname "846-XXXXX_SCH_NEO-M9N_MODULE_2_RECEIVER")
		(sheetfile "846-XXXXX_SCH_NEO-M9N_MODULE_2_RECEIVER.kicad_sch")
		(duplicate_pad_numbers_are_jumpers no)
		(fp_line
			(start 0.9906 -0.5334)
			(end 0.9906 0.5334)
			(stroke
				(width 0.1778)
				(type solid)
			)
			(layer "F.SilkS")
		)
		(fp_line
			(start -0.9906 -0.5334)
			(end 0.9906 -0.5334)
			(stroke
				(width 0.1778)
				(type solid)
			)
			(layer "F.SilkS")
		)
		(fp_line
			(start -0.9906 -0.5334)
			(end -0.9906 0.5334)
			(stroke
				(width 0.1778)
				(type solid)
			)
			(layer "F.SilkS")
		)
		(fp_line
			(start -0.9906 0.5334)
			(end 0.9906 0.5334)
			(stroke
				(width 0.1778)
				(type solid)
			)
			(layer "F.SilkS")
		)
		(pad "1" smd rect
			(at -0.5 0 90)
			(size 0.5 0.6)
			(layers "F.Cu" "F.Mask" "F.Paste")
			(net "GND")
		)
		(pad "2" smd rect
			(at 0.5 0 90)
			(size 0.5 0.6)
			(layers "F.Cu" "F.Mask" "F.Paste")
			(net "NetLED2_2")
		)
	)
)
